(kicad_pcb
	(version 20260206)
	(generator "pcbnew")
	(generator_version "10.0")
	(general
		(thickness 1.6)
		(legacy_teardrops no)
	)
	(paper "A4")
	(title_block
		(title "04192023_DAF0TMB3IC0_F0TG_MB_C_brd_V02_OCP.brd")
		(comment 1 "Grand Teton / footprints 1178-1179 of 8354")
	)
	(layers
		(0 "F.Cu" signal "TOP")
		(4 "In1.Cu" signal "GND")
		(6 "In2.Cu" signal "IN1")
		(8 "In3.Cu" signal "GND1")
		(10 "In4.Cu" signal "IN2")
		(12 "In5.Cu" signal "GND2")
		(14 "In6.Cu" signal "IN3")
		(16 "In7.Cu" signal "GND3")
		(18 "In8.Cu" signal "VCC")
		(20 "In9.Cu" signal "VCC1")
		(22 "In10.Cu" signal "GND4")
		(24 "In11.Cu" signal "IN4")
		(26 "In12.Cu" signal "GND5")
		(28 "In13.Cu" signal "IN5")
		(30 "In14.Cu" signal "GND6")
		(32 "In15.Cu" signal "IN6")
		(34 "In16.Cu" signal "GND7")
		(2 "B.Cu" signal "BOTTOM")
		(9 "F.Adhes" user "F.Adhesive")
		(11 "B.Adhes" user "B.Adhesive")
		(13 "F.Paste" user "Package Geometry/Pastemask Top")
		(15 "B.Paste" user "Package Geometry/Pastemask Bottom")
		(5 "F.SilkS" user "Ref Des/Silkscreen Top")
		(7 "B.SilkS" user "Ref Des/Silkscreen Bottom")
		(1 "F.Mask" user "Board Geometry/Soldermask Top")
		(3 "B.Mask" user "Board Geometry/Soldermask Bottom")
		(17 "Dwgs.User" user "User.Drawings")
		(19 "Cmts.User" user "User.Comments")
		(21 "Eco1.User" user "User.Eco1")
		(23 "Eco2.User" user "User.Eco2")
		(25 "Edge.Cuts" user "Board Geometry/Outline")
		(27 "Margin" user)
		(31 "F.CrtYd" user "Package Geometry/Place Bound Top")
		(29 "B.CrtYd" user "Package Geometry/Place Bound Bottom")
		(35 "F.Fab" user "Ref Des/Assembly Top")
		(33 "B.Fab" user "Ref Des/Assembly Bottom")
	)
	(footprint ""
		(layer "F.Cu")
		(at 257.242056 -125.38837 180)
		(property "Reference" "R3709"
			(at 0 0 180)
			(layer "F.SilkS")
			(hide yes)
			(effects
				(font
					(size 1.27 1.27)
				)
			)
		)
		(property "Value" ""
			(at 0 0 180)
			(layer "F.Fab")
			(effects
				(font
					(size 1.27 1.27)
				)
			)
		)
		(duplicate_pad_numbers_are_jumpers no)
		(fp_line
			(start 0.7874 0.4064)
			(end -0.7874 0.4064)
			(stroke
				(width 0.1524)
				(type default)
			)
			(layer "F.SilkS")
		)
		(fp_line
			(start 0.7874 -0.4064)
			(end 0.7874 0.4064)
			(stroke
				(width 0.1524)
				(type default)
			)
			(layer "F.SilkS")
		)
		(fp_line
			(start -0.7874 0.4064)
			(end -0.7874 -0.4064)
			(stroke
				(width 0.1524)
				(type default)
			)
			(layer "F.SilkS")
		)
		(fp_line
			(start -0.7874 -0.4064)
			(end 0.7874 -0.4064)
			(stroke
				(width 0.1524)
				(type default)
			)
			(layer "F.SilkS")
		)
		(fp_line
			(start 0.67945 0.3048)
			(end 0.120396 0.3048)
			(stroke
				(width 0.1)
				(type default)
			)
			(layer "F.Fab")
		)
		(fp_line
			(start 0.67945 -0.3048)
			(end 0.67945 0.3048)
			(stroke
				(width 0.1)
				(type default)
			)
			(layer "F.Fab")
		)
		(fp_line
			(start 0.12065 -0.2794)
			(end 0.12065 -0.3048)
			(stroke
				(width 0.1)
				(type default)
			)
			(layer "F.Fab")
		)
		(fp_line
			(start 0.12065 -0.3048)
			(end 0.67945 -0.3048)
			(stroke
				(width 0.1)
				(type default)
			)
			(layer "F.Fab")
		)
		(fp_line
			(start 0.120396 0.3048)
			(end 0.120396 0.2794)
			(stroke
				(width 0.1)
				(type default)
			)
			(layer "F.Fab")
		)
		(fp_line
			(start 0.120396 0.2794)
			(end -0.12065 0.2794)
			(stroke
				(width 0.1)
				(type default)
			)
			(layer "F.Fab")
		)
		(fp_line
			(start -0.12065 0.3048)
			(end -0.67945 0.3048)
			(stroke
				(width 0.1)
				(type default)
			)
			(layer "F.Fab")
		)
		(fp_line
			(start -0.12065 0.2794)
			(end -0.12065 0.3048)
			(stroke
				(width 0.1)
				(type default)
			)
			(layer "F.Fab")
		)
		(fp_line
			(start -0.12065 -0.2794)
			(end 0.12065 -0.2794)
			(stroke
				(width 0.1)
				(type default)
			)
			(layer "F.Fab")
		)
		(fp_line
			(start -0.12065 -0.305054)
			(end -0.12065 -0.2794)
			(stroke
				(width 0.1)
				(type default)
			)
			(layer "F.Fab")
		)
		(fp_line
			(start -0.67945 0.3048)
			(end -0.67945 -0.305054)
			(stroke
				(width 0.1)
				(type default)
			)
			(layer "F.Fab")
		)
		(fp_line
			(start -0.67945 -0.305054)
			(end -0.12065 -0.305054)
			(stroke
				(width 0.1)
				(type default)
			)
			(layer "F.Fab")
		)
		(pad "1" smd circle
			(at -0.40005 0 180)
			(size 0 0)
			(layers "F.Cu" "F.Mask" "F.Paste")
			(net "PCA9548_PCIE0_ADDR0")
		)
		(pad "2" smd circle
			(at 0.40005 0 180)
			(size 0 0)
			(layers "F.Cu" "F.Mask" "F.Paste")
			(net "GND")
		)
	)
	(footprint ""
		(layer "F.Cu")
		(at 72.175116 -172.974 90)
		(property "Reference" "PC314"
			(at 0 0 90)
			(layer "F.SilkS")
			(hide yes)
			(effects
				(font
					(size 1.27 1.27)
				)
			)
		)
		(property "Value" ""
			(at 0 0 90)
			(layer "F.Fab")
			(effects
				(font
					(size 1.27 1.27)
				)
			)
		)
		(duplicate_pad_numbers_are_jumpers no)
		(fp_line
			(start 0.7874 -0.4064)
			(end 0.7874 0.4064)
			(stroke
				(width 0.1524)
				(type default)
			)
			(layer "F.SilkS")
		)
		(fp_line
			(start -0.7874 -0.4064)
			(end 0.7874 -0.4064)
			(stroke
				(width 0.1524)
				(type default)
			)
			(layer "F.SilkS")
		)
		(fp_line
			(start 0.7874 0.4064)
			(end -0.7874 0.4064)
			(stroke
				(width 0.1524)
				(type default)
			)
			(layer "F.SilkS")
		)
		(fp_line
			(start -0.7874 0.4064)
			(end -0.7874 -0.4064)
			(stroke
				(width 0.1524)
				(type default)
			)
			(layer "F.SilkS")
		)
		(fp_line
			(start -0.12065 -0.305054)
			(end -0.12065 -0.2794)
			(stroke
				(width 0.1)
				(type default)
			)
			(layer "F.Fab")
		)
		(fp_line
			(start -0.67945 -0.305054)
			(end -0.12065 -0.305054)
			(stroke
				(width 0.1)
				(type default)
			)
			(layer "F.Fab")
		)
		(fp_line
			(start 0.67945 -0.3048)
			(end 0.67945 0.3048)
			(stroke
				(width 0.1)
				(type default)
			)
			(layer "F.Fab")
		)
		(fp_line
			(start 0.12065 -0.3048)
			(end 0.67945 -0.3048)
			(stroke
				(width 0.1)
				(type default)
			)
			(layer "F.Fab")
		)
		(fp_line
			(start 0.12065 -0.2794)
			(end 0.12065 -0.3048)
			(stroke
				(width 0.1)
				(type default)
			)
			(layer "F.Fab")
		)
		(fp_line
			(start -0.12065 -0.2794)
			(end 0.12065 -0.2794)
			(stroke
				(width 0.1)
				(type default)
			)
			(layer "F.Fab")
		)
		(fp_line
			(start 0.120396 0.2794)
			(end -0.12065 0.2794)
			(stroke
				(width 0.1)
				(type default)
			)
			(layer "F.Fab")
		)
		(fp_line
			(start -0.12065 0.2794)
			(end -0.12065 0.3048)
			(stroke
				(width 0.1)
				(type default)
			)
			(layer "F.Fab")
		)
		(fp_line
			(start 0.67945 0.3048)
			(end 0.120396 0.3048)
			(stroke
				(width 0.1)
				(type default)
			)
			(layer "F.Fab")
		)
		(fp_line
			(start 0.120396 0.3048)
			(end 0.120396 0.2794)
			(stroke
				(width 0.1)
				(type default)
			)
			(layer "F.Fab")
		)
		(fp_line
			(start -0.12065 0.3048)
			(end -0.67945 0.3048)
			(stroke
				(width 0.1)
				(type default)
			)
			(layer "F.Fab")
		)
		(fp_line
			(start -0.67945 0.3048)
			(end -0.67945 -0.305054)
			(stroke
				(width 0.1)
				(type default)
			)
			(layer "F.Fab")
		)
		(pad "1" smd circle
			(at -0.40005 0 90)
			(size 0 0)
			(layers "F.Cu" "F.Mask" "F.Paste")
			(net "SW_PVDDCR_CPU0_P1_BOOT5_RC")
		)
		(pad "2" smd circle
			(at 0.40005 0 90)
			(size 0 0)
			(layers "F.Cu" "F.Mask" "F.Paste")
			(net "SW_PVDDCR_CPU0_P1_PH5")
		)
	)
)
